(kicad_pcb
	(version 20241229)
	(generator "pcbnew")
	(generator_version "9.0")
	(general
		(thickness 1.61)
		(legacy_teardrops no)
	)
	(paper "A3")
	(title_block
		(title "RDIMM DDR5 Tester")
		(date "2026-05-21")
		(rev "2.2.0")
		(company "Antmicro")
		(comment 9 "footprints 279-279 of 796")
	)
	(layers
		(0 "F.Cu" signal)
		(4 "In1.Cu" power)
		(6 "In2.Cu" mixed)
		(8 "In3.Cu" power)
		(10 "In4.Cu" mixed)
		(12 "In5.Cu" power)
		(14 "In6.Cu" mixed)
		(16 "In7.Cu" power)
		(18 "In8.Cu" power)
		(20 "In9.Cu" mixed)
		(22 "In10.Cu" power)
		(2 "B.Cu" signal)
		(9 "F.Adhes" user "F.Adhesive")
		(11 "B.Adhes" user "B.Adhesive")
		(13 "F.Paste" user)
		(15 "B.Paste" user)
		(5 "F.SilkS" user "F.Silkscreen")
		(7 "B.SilkS" user "B.Silkscreen")
		(1 "F.Mask" user)
		(3 "B.Mask" user)
		(17 "Dwgs.User" user "User.Drawings")
		(19 "Cmts.User" user "User.Comments")
		(21 "Eco1.User" user "User.Eco1")
		(23 "Eco2.User" user "User.Eco2")
		(25 "Edge.Cuts" user)
		(27 "Margin" user)
		(31 "F.CrtYd" user "F.Courtyard")
		(29 "B.CrtYd" user "B.Courtyard")
		(35 "F.Fab" user)
		(33 "B.Fab" user)
	)
	(footprint "antmicro-footprints:VQFN-48_7x7mm_P0.5mm_EP4.1x4.1mm"
		(layer "F.Cu")
		(at 124.326 181.303 180)
		(property "Reference" "U38"
			(at 6.501 -4.347 0)
			(unlocked yes)
			(layer "F.SilkS")
			(effects
				(font
					(size 0.7 0.7)
					(thickness 0.15)
				)
				(justify left bottom)
			)
		)
		(property "Value" "SN65DP159RGZR"
			(at 0 5.3 180)
			(unlocked yes)
			(layer "F.Fab")
			(effects
				(font
					(size 0.7 0.7)
					(thickness 0.15)
				)
				(justify left bottom)
			)
		)
		(property "Datasheet" "https://www.ti.com/lit/ds/symlink/sn75dp159.pdf?ts=1728245191743&ref_url=https%253A%252F%252Fwww.mouser.de%252F"
			(at 0 0 180)
			(layer "F.Fab")
			(hide yes)
			(effects
				(font
					(size 1.27 1.27)
					(thickness 0.15)
				)
			)
		)
		(property "MPN" "SN65DP159RGZR "
			(at 0 0 180)
			(unlocked yes)
			(layer "F.Fab")
			(hide yes)
			(effects
				(font
					(size 1 1)
					(thickness 0.15)
				)
			)
		)
		(property "Manufacturer" "Texas Instruments"
			(at 0 0 180)
			(unlocked yes)
			(layer "F.Fab")
			(hide yes)
			(effects
				(font
					(size 1 1)
					(thickness 0.15)
				)
			)
		)
		(property "Author" "Antmicro"
			(at 0 0 180)
			(unlocked yes)
			(layer "F.Fab")
			(hide yes)
			(effects
				(font
					(size 1 1)
					(thickness 0.15)
				)
			)
		)
		(property "License" "Apache-2.0"
			(at 0 0 180)
			(unlocked yes)
			(layer "F.Fab")
			(hide yes)
			(effects
				(font
					(size 1 1)
					(thickness 0.15)
				)
			)
		)
		(sheetname "/HDMI + SD Card/")
		(sheetfile "hdmi-sd-card.kicad_sch")
		(attr smd)
		(fp_line
			(start 3.956 3.956)
			(end 3.956 3.218)
			(stroke
				(width 0.15)
				(type solid)
			)
			(layer "F.SilkS")
		)
		(fp_line
			(start 3.956 3.956)
			(end 3.219 3.956)
			(stroke
				(width 0.15)
				(type solid)
			)
			(layer "F.SilkS")
		)
		(fp_line
			(start 3.956 -3.218)
			(end 3.956 -3.956)
			(stroke
				(width 0.15)
				(type solid)
			)
			(layer "F.SilkS")
		)
		(fp_line
			(start 3.956 -3.956)
			(end 3.219 -3.956)
			(stroke
				(width 0.15)
				(type solid)
			)
			(layer "F.SilkS")
		)
		(fp_line
			(start -3.219 3.956)
			(end -3.956 3.956)
			(stroke
				(width 0.15)
				(type solid)
			)
			(layer "F.SilkS")
		)
		(fp_line
			(start -3.219 -3.956)
			(end -3.956 -3.956)
			(stroke
				(width 0.15)
				(type solid)
			)
			(layer "F.SilkS")
		)
		(fp_line
			(start -3.956 3.956)
			(end -3.956 3.218)
			(stroke
				(width 0.15)
				(type solid)
			)
			(layer "F.SilkS")
		)
		(fp_line
			(start -3.956 -3.218)
			(end -3.956 -3.956)
			(stroke
				(width 0.15)
				(type solid)
			)
			(layer "F.SilkS")
		)
		(fp_circle
			(center -4.18 -3.05)
			(end -4.13 -3.05)
			(stroke
				(width 0.15)
				(type solid)
			)
			(fill yes)
			(layer "F.SilkS")
		)
		(fp_rect
			(start -4.3 -4.3)
			(end 4.3 4.3)
			(stroke
				(width 0.05)
				(type solid)
			)
			(fill no)
			(layer "F.CrtYd")
		)
		(fp_line
			(start 3.575 3.575)
			(end 3.575 -3.575)
			(stroke
				(width 0.15)
				(type solid)
			)
			(layer "B.Fab")
		)
		(fp_line
			(start 3.575 3.575)
			(end -3.575 3.575)
			(stroke
				(width 0.15)
				(type solid)
			)
			(layer "B.Fab")
		)
		(fp_line
			(start 3.575 -3.575)
			(end -3.575 -3.575)
			(stroke
				(width 0.15)
				(type solid)
			)
			(layer "B.Fab")
		)
		(fp_line
			(start -3.575 3.575)
			(end -3.575 -3.575)
			(stroke
				(width 0.15)
				(type solid)
			)
			(layer "B.Fab")
		)
		(fp_line
			(start -3.575 -2.305)
			(end -2.305 -3.575)
			(stroke
				(width 0.15)
				(type solid)
			)
			(layer "B.Fab")
		)
		(fp_text user "License: Apache-2.0"
			(at -5.13 9.18 180)
			(layer "F.Fab")
			(effects
				(font
					(size 0.7 0.7)
					(thickness 0.15)
				)
				(justify left bottom)
			)
		)
		(fp_text user "${REFERENCE}"
			(at -5.13 6.78 180)
			(layer "F.Fab")
			(effects
				(font
					(size 0.7 0.7)
					(thickness 0.15)
				)
				(justify left bottom)
			)
		)
		(fp_text user "Author: Antmicro"
			(at -5.13 7.98 180)
			(layer "F.Fab")
			(effects
				(font
					(size 0.7 0.7)
					(thickness 0.15)
				)
				(justify left bottom)
			)
		)
		(pad "1" smd roundrect
			(at -3.475 -2.75 90)
			(size 0.28 0.85)
			(layers "F.Cu" "F.Mask" "F.Paste")
			(roundrect_rratio 0.1785714286)
			(net 707 "/HDMI + SD Card/SWAP{slash}POL")
			(pinfunction "SWAP/POL")
			(pintype "input")
		)
		(pad "2" smd roundrect
			(at -3.475 -2.25 90)
			(size 0.28 0.85)
			(layers "F.Cu" "F.Mask" "F.Paste")
			(roundrect_rratio 0.1785714286)
			(net 294 "/FPGA MGT Interface/HDMI_OUT.D2_P")
			(pinfunction "IN_D2_P")
			(pintype "input")
		)
		(pad "3" smd roundrect
			(at -3.475 -1.75 90)
			(size 0.28 0.85)
			(layers "F.Cu" "F.Mask" "F.Paste")
			(roundrect_rratio 0.1785714286)
			(net 295 "/FPGA MGT Interface/HDMI_OUT.D2_N")
			(pinfunction "IN_D2_N")
			(pintype "input")
		)
		(pad "4" smd roundrect
			(at -3.475 -1.25 90)
			(size 0.28 0.85)
			(layers "F.Cu" "F.Mask" "F.Paste")
			(roundrect_rratio 0.1785714286)
			(net 549 "HDMI_OUT_HPD")
			(pinfunction "HPD_SRC")
			(pintype "output")
		)
		(pad "5" smd roundrect
			(at -3.475 -0.75 90)
			(size 0.28 0.85)
			(layers "F.Cu" "F.Mask" "F.Paste")
			(roundrect_rratio 0.1785714286)
			(net 267 "/FPGA MGT Interface/HDMI_OUT.D1_P")
			(pinfunction "IN_D1_P")
			(pintype "input")
		)
		(pad "6" smd roundrect
			(at -3.475 -0.25 90)
			(size 0.28 0.85)
			(layers "F.Cu" "F.Mask" "F.Paste")
			(roundrect_rratio 0.1785714286)
			(net 290 "/FPGA MGT Interface/HDMI_OUT.D1_N")
			(pinfunction "IN_D1_N")
			(pintype "input")
		)
		(pad "7" smd roundrect
			(at -3.475 0.25 90)
			(size 0.28 0.85)
			(layers "F.Cu" "F.Mask" "F.Paste")
			(roundrect_rratio 0.1785714286)
			(net 1 "GND")
			(pinfunction "GND")
			(pintype "power_in")
		)
		(pad "8" smd roundrect
			(at -3.475 0.75 90)
			(size 0.28 0.85)
			(layers "F.Cu" "F.Mask" "F.Paste")
			(roundrect_rratio 0.1785714286)
			(net 246 "/FPGA MGT Interface/HDMI_OUT.D0_P")
			(pinfunction "IN_D0_P")
			(pintype "input")
		)
		(pad "9" smd roundrect
			(at -3.475 1.25 90)
			(size 0.28 0.85)
			(layers "F.Cu" "F.Mask" "F.Paste")
			(roundrect_rratio 0.1785714286)
			(net 248 "/FPGA MGT Interface/HDMI_OUT.D0_N")
			(pinfunction "IN_D0_N")
			(pintype "input")
		)
		(pad "10" smd roundrect
			(at -3.475 1.75 90)
			(size 0.28 0.85)
			(layers "F.Cu" "F.Mask" "F.Paste")
			(roundrect_rratio 0.1785714286)
			(net 710 "/HDMI + SD Card/I2C_EN{slash}PIN")
			(pinfunction "I2C_EN/PIN")
			(pintype "input")
		)
		(pad "11" smd roundrect
			(at -3.475 2.25 90)
			(size 0.28 0.85)
			(layers "F.Cu" "F.Mask" "F.Paste")
			(roundrect_rratio 0.1785714286)
			(net 381 "/FPGA MGT Interface/HDMI_OUT.CLK_P")
			(pinfunction "IN_CLK_P")
			(pintype "input")
		)
		(pad "12" smd roundrect
			(at -3.475 2.75 90)
			(size 0.28 0.85)
			(layers "F.Cu" "F.Mask" "F.Paste")
			(roundrect_rratio 0.1785714286)
			(net 383 "/FPGA MGT Interface/HDMI_OUT.CLK_N")
			(pinfunction "IN_CLK_N")
			(pintype "input")
		)
		(pad "13" smd roundrect
			(at -2.75 3.475)
			(size 0.28 0.85)
			(layers "F.Cu" "F.Mask" "F.Paste")
			(roundrect_rratio 0.1785714286)
			(net 151 "+3V3")
			(pinfunction "VCC")
			(pintype "power_in")
		)
		(pad "14" smd roundrect
			(at -2.25 3.475)
			(size 0.28 0.85)
			(layers "F.Cu" "F.Mask" "F.Paste")
			(roundrect_rratio 0.1785714286)
			(net 810 "/HDMI + SD Card/HDMI_VDD")
			(pinfunction "VDD")
			(pintype "power_in")
		)
		(pad "15" smd roundrect
			(at -1.75 3.475)
			(size 0.28 0.85)
			(layers "F.Cu" "F.Mask" "F.Paste")
			(roundrect_rratio 0.1785714286)
			(net 769 "/FPGA MGT Interface/HDMI_CTL.SDA")
			(pinfunction "SDA_CTL")
			(pintype "bidirectional")
		)
		(pad "16" smd roundrect
			(at -1.25 3.475)
			(size 0.28 0.85)
			(layers "F.Cu" "F.Mask" "F.Paste")
			(roundrect_rratio 0.1785714286)
			(net 768 "/FPGA MGT Interface/HDMI_CTL.SCL")
			(pinfunction "SCL_CTL")
			(pintype "bidirectional")
		)
		(pad "17" smd roundrect
			(at -0.75 3.475)
			(size 0.28 0.85)
			(layers "F.Cu" "F.Mask" "F.Paste")
			(roundrect_rratio 0.1785714286)
			(net 757 "unconnected-(U38-NC-Pad17)")
			(pinfunction "NC")
			(pintype "no_connect")
		)
		(pad "18" smd roundrect
			(at -0.25 3.475)
			(size 0.28 0.85)
			(layers "F.Cu" "F.Mask" "F.Paste")
			(roundrect_rratio 0.1785714286)
			(net 758 "unconnected-(U38-CEC_EN-Pad18)")
			(pinfunction "CEC_EN")
			(pintype "output+no_connect")
		)
		(pad "19" smd roundrect
			(at 0.25 3.475)
			(size 0.28 0.85)
			(layers "F.Cu" "F.Mask" "F.Paste")
			(roundrect_rratio 0.1785714286)
			(net 1 "GND")
			(pinfunction "GND")
			(pintype "passive")
		)
		(pad "20" smd roundrect
			(at 0.75 3.475)
			(size 0.28 0.85)
			(layers "F.Cu" "F.Mask" "F.Paste")
			(roundrect_rratio 0.1785714286)
			(net 736 "/HDMI + SD Card/PRE_SEL")
			(pinfunction "PRE_SEL")
			(pintype "input")
		)
		(pad "21" smd roundrect
			(at 1.25 3.475)
			(size 0.28 0.85)
			(layers "F.Cu" "F.Mask" "F.Paste")
			(roundrect_rratio 0.1785714286)
			(net 737 "/HDMI + SD Card/EQ_SEL")
			(pinfunction "EQ_SEL/A0")
			(pintype "input")
		)
		(pad "22" smd roundrect
			(at 1.75 3.475)
			(size 0.28 0.85)
			(layers "F.Cu" "F.Mask" "F.Paste")
			(roundrect_rratio 0.1785714286)
			(net 709 "Net-(U38-VSADJ)")
			(pinfunction "VSADJ")
			(pintype "input")
		)
		(pad "23" smd roundrect
			(at 2.25 3.475)
			(size 0.28 0.85)
			(layers "F.Cu" "F.Mask" "F.Paste")
			(roundrect_rratio 0.1785714286)
			(net 810 "/HDMI + SD Card/HDMI_VDD")
			(pinfunction "VDD")
			(pintype "passive")
		)
		(pad "24" smd roundrect
			(at 2.75 3.475)
			(size 0.28 0.85)
			(layers "F.Cu" "F.Mask" "F.Paste")
			(roundrect_rratio 0.1785714286)
			(net 810 "/HDMI + SD Card/HDMI_VDD")
			(pinfunction "VDD")
			(pintype "passive")
		)
		(pad "25" smd roundrect
			(at 3.475 2.75 90)
			(size 0.28 0.85)
			(layers "F.Cu" "F.Mask" "F.Paste")
			(roundrect_rratio 0.1785714286)
			(net 661 "/HDMI + SD Card/HDMI_OUT_CONN_CLK_N")
			(pinfunction "OUT_CLK_N")
			(pintype "output")
		)
		(pad "26" smd roundrect
			(at 3.475 2.25 90)
			(size 0.28 0.85)
			(layers "F.Cu" "F.Mask" "F.Paste")
			(roundrect_rratio 0.1785714286)
			(net 660 "/HDMI + SD Card/HDMI_OUT_CONN_CLK_P")
			(pinfunction "OUT_CLK_P")
			(pintype "output")
		)
		(pad "27" smd roundrect
			(at 3.475 1.75 90)
			(size 0.28 0.85)
			(layers "F.Cu" "F.Mask" "F.Paste")
			(roundrect_rratio 0.1785714286)
			(net 738 "/HDMI + SD Card/~{HDMI_SEL}")
			(pinfunction "~{HDMI_SEL}/A1")
			(pintype "input")
		)
		(pad "28" smd roundrect
			(at 3.475 1.25 90)
			(size 0.28 0.85)
			(layers "F.Cu" "F.Mask" "F.Paste")
			(roundrect_rratio 0.1785714286)
			(net 659 "/HDMI + SD Card/HDMI_OUT_CONN_D0_N")
			(pinfunction "OUT_D0_N")
			(pintype "output")
		)
		(pad "29" smd roundrect
			(at 3.475 0.75 90)
			(size 0.28 0.85)
			(layers "F.Cu" "F.Mask" "F.Paste")
			(roundrect_rratio 0.1785714286)
			(net 658 "/HDMI + SD Card/HDMI_OUT_CONN_D0_P")
			(pinfunction "OUT_D0_P")
			(pintype "output")
		)
		(pad "30" smd roundrect
			(at 3.475 0.25 90)
			(size 0.28 0.85)
			(layers "F.Cu" "F.Mask" "F.Paste")
			(roundrect_rratio 0.1785714286)
			(net 1 "GND")
			(pinfunction "GND")
			(pintype "passive")
		)
		(pad "31" smd roundrect
			(at 3.475 -0.25 90)
			(size 0.28 0.85)
			(layers "F.Cu" "F.Mask" "F.Paste")
			(roundrect_rratio 0.1785714286)
			(net 657 "/HDMI + SD Card/HDMI_OUT_CONN_D1_N")
			(pinfunction "OUT_D1_N")
			(pintype "output")
		)
		(pad "32" smd roundrect
			(at 3.475 -0.75 90)
			(size 0.28 0.85)
			(layers "F.Cu" "F.Mask" "F.Paste")
			(roundrect_rratio 0.1785714286)
			(net 656 "/HDMI + SD Card/HDMI_OUT_CONN_D1_P")
			(pinfunction "OUT_D1_P")
			(pintype "output")
		)
		(pad "33" smd roundrect
			(at 3.475 -1.25 90)
			(size 0.28 0.85)
			(layers "F.Cu" "F.Mask" "F.Paste")
			(roundrect_rratio 0.1785714286)
			(net 530 "Net-(U38-HPD_SNK)")
			(pinfunction "HPD_SNK")
			(pintype "input")
		)
		(pad "34" smd roundrect
			(at 3.475 -1.75 90)
			(size 0.28 0.85)
			(layers "F.Cu" "F.Mask" "F.Paste")
			(roundrect_rratio 0.1785714286)
			(net 655 "/HDMI + SD Card/HDMI_OUT_CONN_D2_N")
			(pinfunction "OUT_D2_N")
			(pintype "output")
		)
		(pad "35" smd roundrect
			(at 3.475 -2.25 90)
			(size 0.28 0.85)
			(layers "F.Cu" "F.Mask" "F.Paste")
			(roundrect_rratio 0.1785714286)
			(net 654 "/HDMI + SD Card/HDMI_OUT_CONN_D2_P")
			(pinfunction "OUT_D2_P")
			(pintype "output")
		)
		(pad "36" smd roundrect
			(at 3.475 -2.75 90)
			(size 0.28 0.85)
			(layers "F.Cu" "F.Mask" "F.Paste")
			(roundrect_rratio 0.1785714286)
			(net 739 "/HDMI + SD Card/TX_TERM_CTL")
			(pinfunction "TX_TERM_CTL")
			(pintype "input")
		)
		(pad "37" smd roundrect
			(at 2.75 -3.475)
			(size 0.28 0.85)
			(layers "F.Cu" "F.Mask" "F.Paste")
			(roundrect_rratio 0.1785714286)
			(net 810 "/HDMI + SD Card/HDMI_VDD")
			(pinfunction "VDD")
			(pintype "passive")
		)
		(pad "38" smd roundrect
			(at 2.25 -3.475)
			(size 0.28 0.85)
			(layers "F.Cu" "F.Mask" "F.Paste")
			(roundrect_rratio 0.1785714286)
			(net 467 "/HDMI + SD Card/HDMI_OUT_C.SCL")
			(pinfunction "SCL_SNK")
			(pintype "bidirectional")
		)
		(pad "39" smd roundrect
			(at 1.75 -3.475)
			(size 0.28 0.85)
			(layers "F.Cu" "F.Mask" "F.Paste")
			(roundrect_rratio 0.1785714286)
			(net 468 "/HDMI + SD Card/HDMI_OUT_C.SDA")
			(pinfunction "SDA_SNK")
			(pintype "bidirectional")
		)
		(pad "40" smd roundrect
			(at 1.25 -3.475)
			(size 0.28 0.85)
			(layers "F.Cu" "F.Mask" "F.Paste")
			(roundrect_rratio 0.1785714286)
			(net 740 "/HDMI + SD Card/SLEW_CTL")
			(pinfunction "SLEW_CTL")
			(pintype "input")
		)
		(pad "41" smd roundrect
			(at 0.75 -3.475)
			(size 0.28 0.85)
			(layers "F.Cu" "F.Mask" "F.Paste")
			(roundrect_rratio 0.1785714286)
			(net 1 "GND")
			(pinfunction "GND")
			(pintype "passive")
		)
		(pad "42" smd roundrect
			(at 0.25 -3.475)
			(size 0.28 0.85)
			(layers "F.Cu" "F.Mask" "F.Paste")
			(roundrect_rratio 0.1785714286)
			(net 385 "HDMI_OE")
			(pinfunction "OE")
			(pintype "input")
		)
		(pad "43" smd roundrect
			(at -0.25 -3.475)
			(size 0.28 0.85)
			(layers "F.Cu" "F.Mask" "F.Paste")
			(roundrect_rratio 0.1785714286)
			(net 151 "+3V3")
			(pinfunction "VCC")
			(pintype "passive")
		)
		(pad "44" smd roundrect
			(at -0.75 -3.475)
			(size 0.28 0.85)
			(layers "F.Cu" "F.Mask" "F.Paste")
			(roundrect_rratio 0.1785714286)
			(net 759 "unconnected-(U38-AUX_SRC_N-Pad44)")
			(pinfunction "AUX_SRC_N")
			(pintype "bidirectional+no_connect")
		)
		(pad "45" smd roundrect
			(at -1.25 -3.475)
			(size 0.28 0.85)
			(layers "F.Cu" "F.Mask" "F.Paste")
			(roundrect_rratio 0.1785714286)
			(net 760 "unconnected-(U38-AUX_SRC_P-Pad45)")
			(pinfunction "AUX_SRC_P")
			(pintype "bidirectional+no_connect")
		)
		(pad "46" smd roundrect
			(at -1.75 -3.475)
			(size 0.28 0.85)
			(layers "F.Cu" "F.Mask" "F.Paste")
			(roundrect_rratio 0.1785714286)
			(net 554 "/FPGA banks HD/HDMI_OUT_I2C.SCL")
			(pinfunction "SCL_SRC")
			(pintype "bidirectional")
		)
		(pad "47" smd roundrect
			(at -2.25 -3.475)
			(size 0.28 0.85)
			(layers "F.Cu" "F.Mask" "F.Paste")
			(roundrect_rratio 0.1785714286)
			(net 644 "/FPGA banks HD/HDMI_OUT_I2C.SDA")
			(pinfunction "SDA_SRC")
			(pintype "bidirectional")
		)
		(pad "48" smd roundrect
			(at -2.75 -3.475)
			(size 0.28 0.85)
			(layers "F.Cu" "F.Mask" "F.Paste")
			(roundrect_rratio 0.1785714286)
			(net 810 "/HDMI + SD Card/HDMI_VDD")
			(pinfunction "VDD")
			(pintype "passive")
		)
		(pad "49" smd roundrect
			(at 0 0 180)
			(size 4.1 4.1)
			(layers "F.Cu" "F.Mask" "F.Paste")
			(roundrect_rratio 0.01219512195)
			(net 1 "GND")
			(pinfunction "GND")
			(pintype "passive")
			(solder_paste_margin_ratio -0.1)
		)
	)
)
